# S9S_MB_2U (Grand Teton) — schematic netlist excerpt (pin names and nets, part order shuffled) for the footprints in the layout excerpt that follows; sources: Cadence DE-HDL packaged netlist, KiCad conversion of 03242023_DA0F0TMBIJ0_F0T_Motherboard_J_brd_V01_OCP.brd

U70  MOSFET_N  BSS138K IC  pkg SMLF  page 223
  DRAIN  = FM_PLD_CLKS_OE_R_N
  GATE  = FM_PLD_CLKS_DEV_EN
  SOURCE  = GND

C154  Q_CAP_DIFFBUS  DIFF BUS_0.22UF 6.3V 20% X6S  pkg C0201  page 178 : \1\ = DMI_CPU0_PCH_TX_C_DP<0> ; \2\ = DMI_CPU0_PCH_TX_DP<0>
C680  Q_CAP_DIFFBUS  DIFF BUS_0.22UF 6.3V 20% X6S  pkg C0201  page 177 : \1\ = P5E_CPU1_PE4_TX_C_DN<14> ; \2\ = P5E_CPU1_PE4_TX_DN<14>
C2148  Q_CAP  0.01UF 50V 10% EMPTY  pkg C0402  page 162 : A = P12V_OCP_V3_2 ; B = P12V_OCP_GATE_2

(kicad_pcb
	(version 20260206)
	(generator "pcbnew")
	(generator_version "10.0")
	(general
		(thickness 1.6)
		(legacy_teardrops no)
	)
	(paper "A4")
	(title_block
		(title "03242023_DA0F0TMBIJ0_F0T_Motherboard_J_brd_V01_OCP.brd")
		(comment 1 "Grand Teton / footprints 41-44 of 6105")
	)
	(layers
		(0 "F.Cu" signal "TOP")
		(4 "In1.Cu" signal "GND")
		(6 "In2.Cu" signal "IN1")
		(8 "In3.Cu" signal "GND1")
		(10 "In4.Cu" signal "IN2")
		(12 "In5.Cu" signal "GND2")
		(14 "In6.Cu" signal "IN3")
		(16 "In7.Cu" signal "GND3")
		(18 "In8.Cu" signal "VCC")
		(20 "In9.Cu" signal "VCC1")
		(22 "In10.Cu" signal "GND4")
		(24 "In11.Cu" signal "IN4")
		(26 "In12.Cu" signal "GND5")
		(28 "In13.Cu" signal "IN5")
		(30 "In14.Cu" signal "GND6")
		(32 "In15.Cu" signal "IN6")
		(34 "In16.Cu" signal "GND7")
		(2 "B.Cu" signal "BOTTOM")
		(9 "F.Adhes" user "F.Adhesive")
		(11 "B.Adhes" user "B.Adhesive")
		(13 "F.Paste" user "Package Geometry/Pastemask Top")
		(15 "B.Paste" user "Package Geometry/Pastemask Bottom")
		(5 "F.SilkS" user "Ref Des/Silkscreen Top")
		(7 "B.SilkS" user "Ref Des/Silkscreen Bottom")
		(1 "F.Mask" user "Board Geometry/Soldermask Top")
		(3 "B.Mask" user "Board Geometry/Soldermask Bottom")
		(17 "Dwgs.User" user "User.Drawings")
		(19 "Cmts.User" user "User.Comments")
		(21 "Eco1.User" user "User.Eco1")
		(23 "Eco2.User" user "User.Eco2")
		(25 "Edge.Cuts" user "Board Geometry/Outline")
		(27 "Margin" user)
		(31 "F.CrtYd" user "Package Geometry/Place Bound Top")
		(29 "B.CrtYd" user "Package Geometry/Place Bound Bottom")
		(35 "F.Fab" user "Ref Des/Assembly Top")
		(33 "B.Fab" user "Ref Des/Assembly Bottom")
	)
	(footprint ""
		(layer "F.Cu")
		(at 80.913478 -24.333962 180)
		(property "Reference" "C2148"
			(at 0 0 180)
			(layer "F.SilkS")
			(hide yes)
			(effects
				(font
					(size 1.27 1.27)
				)
			)
		)
		(property "Value" ""
			(at 0 0 180)
			(layer "F.Fab")
			(effects
				(font
					(size 1.27 1.27)
				)
			)
		)
		(duplicate_pad_numbers_are_jumpers no)
		(fp_line
			(start 0.7874 0.4064)
			(end -0.7874 0.4064)
			(stroke
				(width 0.1524)
				(type default)
			)
			(layer "F.SilkS")
		)
		(fp_line
			(start 0.7874 -0.4064)
			(end 0.7874 0.4064)
			(stroke
				(width 0.1524)
				(type default)
			)
			(layer "F.SilkS")
		)
		(fp_line
			(start -0.7874 0.4064)
			(end -0.7874 -0.4064)
			(stroke
				(width 0.1524)
				(type default)
			)
			(layer "F.SilkS")
		)
		(fp_line
			(start -0.7874 -0.4064)
			(end 0.7874 -0.4064)
			(stroke
				(width 0.1524)
				(type default)
			)
			(layer "F.SilkS")
		)
		(fp_line
			(start 0.67945 0.3048)
			(end 0.120396 0.3048)
			(stroke
				(width 0.1)
				(type default)
			)
			(layer "F.Fab")
		)
		(fp_line
			(start 0.67945 -0.3048)
			(end 0.67945 0.3048)
			(stroke
				(width 0.1)
				(type default)
			)
			(layer "F.Fab")
		)
		(fp_line
			(start 0.12065 -0.2794)
			(end 0.12065 -0.3048)
			(stroke
				(width 0.1)
				(type default)
			)
			(layer "F.Fab")
		)
		(fp_line
			(start 0.12065 -0.3048)
			(end 0.67945 -0.3048)
			(stroke
				(width 0.1)
				(type default)
			)
			(layer "F.Fab")
		)
		(fp_line
			(start 0.120396 0.3048)
			(end 0.120396 0.2794)
			(stroke
				(width 0.1)
				(type default)
			)
			(layer "F.Fab")
		)
		(fp_line
			(start 0.120396 0.2794)
			(end -0.12065 0.2794)
			(stroke
				(width 0.1)
				(type default)
			)
			(layer "F.Fab")
		)
		(fp_line
			(start -0.12065 0.3048)
			(end -0.67945 0.3048)
			(stroke
				(width 0.1)
				(type default)
			)
			(layer "F.Fab")
		)
		(fp_line
			(start -0.12065 0.2794)
			(end -0.12065 0.3048)
			(stroke
				(width 0.1)
				(type default)
			)
			(layer "F.Fab")
		)
		(fp_line
			(start -0.12065 -0.2794)
			(end 0.12065 -0.2794)
			(stroke
				(width 0.1)
				(type default)
			)
			(layer "F.Fab")
		)
		(fp_line
			(start -0.12065 -0.305054)
			(end -0.12065 -0.2794)
			(stroke
				(width 0.1)
				(type default)
			)
			(layer "F.Fab")
		)
		(fp_line
			(start -0.67945 0.3048)
			(end -0.67945 -0.305054)
			(stroke
				(width 0.1)
				(type default)
			)
			(layer "F.Fab")
		)
		(fp_line
			(start -0.67945 -0.305054)
			(end -0.12065 -0.305054)
			(stroke
				(width 0.1)
				(type default)
			)
			(layer "F.Fab")
		)
		(pad "1" smd circle
			(at -0.40005 0 180)
			(size 0 0)
			(layers "F.Cu" "F.Mask" "F.Paste")
			(net "P12V_OCP_V3_2")
		)
		(pad "2" smd circle
			(at 0.40005 0 180)
			(size 0 0)
			(layers "F.Cu" "F.Mask" "F.Paste")
			(net "P12V_OCP_GATE_2")
		)
	)
	(footprint ""
		(layer "F.Cu")
		(at 341.52459 -70.03796 90)
		(property "Reference" "C154"
			(at 0 0 90)
			(layer "F.SilkS")
			(hide yes)
			(effects
				(font
					(size 1.27 1.27)
				)
			)
		)
		(property "Value" ""
			(at 0 0 90)
			(layer "F.Fab")
			(effects
				(font
					(size 1.27 1.27)
				)
			)
		)
		(duplicate_pad_numbers_are_jumpers no)
		(fp_line
			(start 0.299974 -0.150114)
			(end 0.299974 0.150114)
			(stroke
				(width 0.1)
				(type default)
			)
			(layer "F.Fab")
		)
		(fp_line
			(start -0.299974 -0.150114)
			(end 0.299974 -0.150114)
			(stroke
				(width 0.1)
				(type default)
			)
			(layer "F.Fab")
		)
		(fp_line
			(start 0.299974 0.150114)
			(end -0.299974 0.150114)
			(stroke
				(width 0.1)
				(type default)
			)
			(layer "F.Fab")
		)
		(fp_line
			(start -0.299974 0.150114)
			(end -0.299974 -0.150114)
			(stroke
				(width 0.1)
				(type default)
			)
			(layer "F.Fab")
		)
		(pad "1" smd rect
			(at -0.2667 0 90)
			(size 0.3048 0.381)
			(layers "F.Cu" "F.Mask" "F.Paste")
			(net "DMI_CPU0_PCH_TX_C_DP<0>")
		)
		(pad "2" smd rect
			(at 0.2667 0 90)
			(size 0.3048 0.381)
			(layers "F.Cu" "F.Mask" "F.Paste")
			(net "DMI_CPU0_PCH_TX_DP<0>")
		)
	)
	(footprint ""
		(layer "F.Cu")
		(at 92.185998 -408.517344 -90)
		(property "Reference" "C680"
			(at 0 0 270)
			(layer "F.SilkS")
			(hide yes)
			(effects
				(font
					(size 1.27 1.27)
				)
			)
		)
		(property "Value" ""
			(at 0 0 270)
			(layer "F.Fab")
			(effects
				(font
					(size 1.27 1.27)
				)
			)
		)
		(duplicate_pad_numbers_are_jumpers no)
		(fp_line
			(start -0.299974 0.150114)
			(end -0.299974 -0.150114)
			(stroke
				(width 0.1)
				(type default)
			)
			(layer "F.Fab")
		)
		(fp_line
			(start 0.299974 0.150114)
			(end -0.299974 0.150114)
			(stroke
				(width 0.1)
				(type default)
			)
			(layer "F.Fab")
		)
		(fp_line
			(start -0.299974 -0.150114)
			(end 0.299974 -0.150114)
			(stroke
				(width 0.1)
				(type default)
			)
			(layer "F.Fab")
		)
		(fp_line
			(start 0.299974 -0.150114)
			(end 0.299974 0.150114)
			(stroke
				(width 0.1)
				(type default)
			)
			(layer "F.Fab")
		)
		(pad "1" smd rect
			(at -0.2667 0 270)
			(size 0.3048 0.381)
			(layers "F.Cu" "F.Mask" "F.Paste")
			(net "P5E_CPU1_PE4_TX_C_DN<14>")
		)
		(pad "2" smd rect
			(at 0.2667 0 270)
			(size 0.3048 0.381)
			(layers "F.Cu" "F.Mask" "F.Paste")
			(net "P5E_CPU1_PE4_TX_DN<14>")
		)
	)
	(footprint ""
		(layer "F.Cu")
		(at 270.08582 -93.970348 90)
		(property "Reference" "U70"
			(at -2.84099 -0.26416 0)
			(unlocked yes)
			(layer "F.SilkS")
			(effects
				(font
					(size 0.7874 0.5842)
					(thickness 0.1524)
				)
			)
		)
		(property "Value" ""
			(at 0 0 90)
			(layer "F.Fab")
			(effects
				(font
					(size 1.27 1.27)
				)
			)
		)
		(duplicate_pad_numbers_are_jumpers no)
		(fp_line
			(start -1.949958 -1.610106)
			(end 1.949958 -1.610106)
			(stroke
				(width 0.1524)
				(type default)
			)
			(layer "F.SilkS")
		)
		(fp_line
			(start 1.949958 -1.560068)
			(end 1.949958 1.610106)
			(stroke
				(width 0.1524)
				(type default)
			)
			(layer "F.SilkS")
		)
		(fp_line
			(start 1.949958 1.610106)
			(end -1.949958 1.610106)
			(stroke
				(width 0.1524)
				(type default)
			)
			(layer "F.SilkS")
		)
		(fp_line
			(start -1.949958 1.610106)
			(end -1.949958 -1.610106)
			(stroke
				(width 0.1524)
				(type default)
			)
			(layer "F.SilkS")
		)
		(fp_line
			(start 0.750062 -1.560068)
			(end 0.750062 1.560068)
			(stroke
				(width 0.1)
				(type default)
			)
			(layer "F.Fab")
		)
		(fp_line
			(start -0.750062 -1.560068)
			(end 0.750062 -1.560068)
			(stroke
				(width 0.1)
				(type default)
			)
			(layer "F.Fab")
		)
		(fp_line
			(start 0.750062 1.560068)
			(end -0.750062 1.560068)
			(stroke
				(width 0.1)
				(type default)
			)
			(layer "F.Fab")
		)
		(fp_line
			(start -0.750062 1.560068)
			(end -0.750062 -1.560068)
			(stroke
				(width 0.1)
				(type default)
			)
			(layer "F.Fab")
		)
		(pad "D" smd rect
			(at 1.100074 0)
			(size 1.016 1.4224)
			(layers "F.Cu" "F.Mask" "F.Paste")
			(net "FM_PLD_CLKS_OE_R_N")
		)
		(pad "G" smd rect
			(at -1.100074 -0.94996)
			(size 1.016 1.4224)
			(layers "F.Cu" "F.Mask" "F.Paste")
			(net "FM_PLD_CLKS_DEV_EN")
		)
		(pad "S" smd rect
			(at -1.100074 0.94996)
			(size 1.016 1.4224)
			(layers "F.Cu" "F.Mask" "F.Paste")
			(net "GND")
		)
	)
)
